FILE_TYPE = MACRO_DRAWING;
SET COLOR_WIRE YELLOW;
SET COLOR_PROP ORANGE;
SET COLOR_DOT WHITE;
SET COLOR_ARC YELLOW;
SET COLOR_BODY GREEN;
SET COLOR_NOTE PURPLE;
SET PROP_DISPLAY VALUE;
SET PAGE_NUMBER P6;
FORCEADD QUANTA_TITLE_BLOCK_C..1
(-100 100);
FORCEPROP 1 LAST CUSTOM_TXT_CDS <NAME_2>
J 0
(-3275 150);
FORCEPROP 1 LAST CUSTOM_TXT_CDS <NAME_1>
J 0
(-3275 275);
FORCEPROP 1 LAST CUSTOM_TXT_CDS <Q_NUMBER>
J 0
(-1503 203);
DISPLAY 1.212766 (-1503 203);
FORCEPROP 1 LAST CUSTOM_TXT_CDS <Q_PROJ>
J 0
(-2482 202);
DISPLAY 1.212766 (-2482 202);
FORCEPROP 1 LAST CUSTOM_TXT_CDS <Q_REV>
J 0
(-284 203);
DISPLAY 1.212766 (-284 203);
FORCEPROP 1 LAST CUSTOM_TXT_CDS <CON_LAST_MODIFIED>
J 0
(-1985 115);
DISPLAY 0.978723 (-1985 115);
FORCEPROP 1 LAST CUSTOM_TXT_CDS <CON_PAGE_NUM> OF <CON_TOTAL_PAGES>
J 0
(-546 118);
DISPLAY 0.978723 (-546 118);
FORCEPROP 1 LAST Q_TITLE BLOCK DIAGRAM - POWER
J 0
(-9400 150);
DISPLAY 2.446809 (-9400 150);
PAINT GREEN (-9400 150);
FORCEPROP 2 LAST PAGE_BORDER TRUE
J 0
(-7990 5350);
DISPLAY 0.638298 (-7990 5350);
PAINT PINK (-7990 5350);
DISPLAY INVISIBLE (-7990 5350);
FORCEPROP 1 LAST CDS_LMAN_SYM_OUTLINE -9475,6775,100,-125
J 0
(-100 100);
DISPLAY 0.468085 (-100 100);
PAINT GREEN (-100 100);
DISPLAY INVISIBLE (-100 100);
FORCEPROP 2 LAST CDS_LIB pure_quanta
J 0
(-100 100);
DISPLAY INVISIBLE (-100 100);
FORCEPROP 2 LAST CDS_XR_PAGE_TITLE CR-6 : @T6G_MB_LIB.T6G(SCH_1):PAGE6
J 0
(-7990 5350);
DISPLAY 0.638298 (-7990 5350);
PAINT PINK (-7990 5350);
DISPLAY INVISIBLE (-7990 5350);
FORCEPROP 2 LAST CUSTOM_TXT_CDS <XR_PAGE_TITLE>
J 0
(-7990 5350);
DISPLAY 0.638298 (-7990 5350);
PAINT PINK (-7990 5350);
DISPLAY INVISIBLE (-7990 5350);
FORCEPROP 1 LAST COMMENT_BODY TRUE
J 0
(-88 87);
DISPLAY 0.978723 (-88 87);
PAINT GREEN (-88 87);
DISPLAY INVISIBLE (-88 87);
FORCEPROP 1 LAST Q_DEPT BU9
J 1
(-3863 149);
DISPLAY 1.957447 (-3863 149);
PAINT GREEN (-3863 149);
DISPLAY INVISIBLE (-3863 149);
FORCEPROP 0 LAST CDS_CON_LAST_MODIFIED Thu Aug 24 10:13:30 2023
J 0
(-1985 115);
DISPLAY INVISIBLE (-1985 115);
FORCENOTE
$CDS_IMAGE|Grand_Teton_Inference_8 Retimer_Block_Diagram_20230203_REV3-PWR.jpg|5140|5820
(-5200 3475) 0;
DISPLAY LEFT (-5200 3475);
QUIT
